# S9S_MB_2U (Grand Teton) — schematic parts with pin connectivity, parts 5876–5876 of 6093; source: Cadence DE-HDL packaged netlist (pstxprt.dat, pstxnet.dat, pstchip.dat)

U1  SOCKET4677_AZIF0045P001C01CS  SOCKET4677_AZIF0045-P001C01CS IO  pkg SOCKET4677_82X64-5XA_H466  page 44  (pins 3925-4251 of 4677)
  EP47  DDR4_SA_CA5  OUT  = M_E_CPU1_SA_CA<5>
  EP49  DDR4_SA_CA0  OUT  = M_E_CPU1_SA_CA<0>
  EP51  DDR4_SA_CS_N0  OUT  = M_E_CPU1_SA_CS_N<0>
  EP53  DDR4_SA_ECC7  BI  = M_E_CPU1_SA_CB<7>
  EP55  DDR4_SA_DQS_DP9  BI  = M_E_CPU1_SA_DQS_DP<9>
  EP57  DDR4_SA_ECC2  BI  = M_E_CPU1_SA_CB<2>
  EP59  DDR4_SA_DQ31  BI  = M_E_CPU1_SA_DQ<31>
  EP61  DDR4_SA_DQS_DP8  BI  = M_E_CPU1_SA_DQS_DP<8>
  EP63  DDR4_SA_DQ26  BI  = M_E_CPU1_SA_DQ<26>
  EP65  DDR4_SA_DQ23  BI  = M_E_CPU1_SA_DQ<23>
  EP67  VSS1543  POWER  = GND
  EP69  VSS1452  POWER  = GND
  EP71  VSS1453  POWER  = GND
  EP73  DDR4_SA_DQ6  BI  = M_E_CPU1_SA_DQ<6>
  EP75  DDR4_SA_DQS_DN0  BI  = M_E_CPU1_SA_DQS_DN<0>
  EP77  VSS1454  POWER  = GND
  EP79  DDR4_SA_DQ2  BI  = M_E_CPU1_SA_DQ<2>
  EP81  UPI3_RX_DN1  IN  = GND
  EP83  VSS1545  POWER  = GND
  EP85  UPI3_TX_DN2  OUT  = NC
  EP87  UPI3_TX_DP3  OUT  = NC
  ER5  VSS1549  POWER  = GND
  ER7  VSS1550  POWER  = GND
  ER9  VSS1476  POWER  = GND
  ER11  DDR5_SB_DQ22  BI  = M_F_CPU1_SB_DQ<22>
  ER13  DDR5_SB_DQ19  BI  = M_F_CPU1_SB_DQ<19>
  ER15  VSS1456  POWER  = GND
  ER17  DDR4_SB_DQ30  BI  = M_E_CPU1_SB_DQ<30>
  ER19  DDR4_SB_DQ27  BI  = M_E_CPU1_SB_DQ<27>
  ER21  VSS1457  POWER  = GND
  ER23  DDR4_SB_DQ22  BI  = M_E_CPU1_SB_DQ<22>
  ER25  DDR4_SB_DQ19  BI  = M_E_CPU1_SB_DQ<19>
  ER27  VSS1547  POWER  = GND
  ER29  DDR4_SB_DQ14  BI  = M_E_CPU1_SB_DQ<14>
  ER31  DDR4_SB_DQ11  BI  = M_E_CPU1_SB_DQ<11>
  ER33  VSS1548  POWER  = GND
  ER35  DDR4_SB_ECC2  BI  = M_E_CPU1_SB_CB<2>
  ER37  DDR4_SB_ECC7  BI  = M_E_CPU1_SB_CB<7>
  ER39  VSS1462  POWER  = GND
  ER41  VSS1834  POWER  = GND
  ER43  VSS1835  POWER  = GND
  ER48  VSS1836  POWER  = GND
  ER50  VSS1837  POWER  = GND
  ER52  VSS1464  POWER  = GND
  ER54  DDR4_SA_ECC6  BI  = M_E_CPU1_SA_CB<6>
  ER56  DDR4_SA_ECC3  BI  = M_E_CPU1_SA_CB<3>
  ER58  VSS1467  POWER  = GND
  ER60  DDR4_SA_DQ30  BI  = M_E_CPU1_SA_DQ<30>
  ER62  DDR4_SA_DQ27  BI  = M_E_CPU1_SA_DQ<27>
  ER64  VSS1468  POWER  = GND
  ER66  DDR4_SA_DQ20  BI  = M_E_CPU1_SA_DQ<20>
  ER68  DDR4_SA_DQ19  BI  = M_E_CPU1_SA_DQ<19>
  ER70  VSS1551  POWER  = GND
  ER72  DDR4_SA_DQ7  BI  = M_E_CPU1_SA_DQ<7>
  ER74  VSS1552  POWER  = GND
  ER76  DDR4_SA_DQ3  BI  = M_E_CPU1_SA_DQ<3>
  ER78  VSS1553  POWER  = GND
  ER80  VSS1554  POWER  = GND
  ER82  UPI3_RX_DP1  IN  = GND
  ER84  VSS1555  POWER  = GND
  ER86  VSS1556  POWER  = GND
  ET8  DDR6_SB_DQ27  BI  = M_G_CPU1_SB_DQ<27>
  ET10  VSS1557  POWER  = GND
  ET12  DDR5_SB_DQS_DN7  BI  = M_F_CPU1_SB_DQS_DN<7>
  ET14  VSS1478  POWER  = GND
  ET16  VSS1559  POWER  = GND
  ET18  DDR4_SB_DQS_DN8  BI  = M_E_CPU1_SB_DQS_DN<8>
  ET20  VSS1480  POWER  = GND
  ET22  VSS1561  POWER  = GND
  ET24  DDR4_SB_DQS_DN7  BI  = M_E_CPU1_SB_DQS_DN<7>
  ET26  VSS1482  POWER  = GND
  ET28  VSS1562  POWER  = GND
  ET30  DDR4_SB_DQS_DN6  BI  = M_E_CPU1_SB_DQS_DN<6>
  ET32  VSS1484  POWER  = GND
  ET34  VSS1563  POWER  = GND
  ET36  DDR4_SB_DQS_DN4  BI  = M_E_CPU1_SB_DQS_DN<4>
  ET38  VSS1565  POWER  = GND
  ET40  DDR4_SB_CS_N1  OUT  = M_E_CPU1_SB_CS_N<1>
  ET42  DDR4_SB_CA5  OUT  = M_E_CPU1_SB_CA<5>
  ET49  DDR4_SA_CA1  OUT  = M_E_CPU1_SA_CA<1>
  ET51  DDR4_SA_CS_N1  OUT  = M_E_CPU1_SA_CS_N<1>
  ET53  VSS1491  POWER  = GND
  ET55  DDR4_SA_DQS_DN9  BI  = M_E_CPU1_SA_DQS_DN<9>
  ET57  VSS1569  POWER  = GND
  ET59  VSS1493  POWER  = GND
  ET61  DDR4_SA_DQS_DN8  BI  = M_E_CPU1_SA_DQS_DN<8>
  F4  VSS1573  POWER  = GND
  F6  VSS1507  POWER  = GND
  F8  DDR0_SB_DQ30  BI  = M_A_CPU1_SB_DQ<30>
  F10  DDR0_SB_DQ27  BI  = M_A_CPU1_SB_DQ<27>
  F12  VSS1494  POWER  = GND
  F14  DDR1_SB_DQ31  BI  = M_B_CPU1_SB_DQ<31>
  F16  DDR1_SB_DQ27  BI  = M_B_CPU1_SB_DQ<27>
  F18  VSS1495  POWER  = GND
  F20  DDR0_SB_DQ22  BI  = M_A_CPU1_SB_DQ<22>
  F22  DDR0_SB_DQ19  BI  = M_A_CPU1_SB_DQ<19>
  F24  VSS1570  POWER  = GND
  F26  DDR0_SB_DQ14  BI  = M_A_CPU1_SB_DQ<14>
  F28  DDR0_SB_DQ11  BI  = M_A_CPU1_SB_DQ<11>
  F30  VSS1571  POWER  = GND
  F32  DDR0_SB_ECC2  BI  = M_A_CPU1_SB_CB<2>
  F34  DDR0_SB_ECC7  BI  = M_A_CPU1_SB_CB<7>
  F36  VSS1572  POWER  = GND
  F38  DDR0_SB_CS_N2  OUT  = M_A_CPU1_SB_CS_N<2>
  F40  DDR0_SB_CA5  OUT  = M_A_CPU1_SB_CA<5>
  F42  VSS1502  POWER  = GND
  F44  DDR0_SB_CA1  OUT  = M_A_CPU1_SB_CA<1>
  F47  DDR23_DRAM_PWR_OK  IN  = PWRGD_DRAMPWRGD_CPU1_CD_LVC1_R
  F49  VSS1574  POWER  = GND
  F51  DDR0_SA_CA3  OUT  = M_A_CPU1_SA_CA<3>
  F53  DDR0_SA_CS_N3  OUT  = M_A_CPU1_SA_CS_N<3>
  F55  VSS1504  POWER  = GND
  F57  DDR0_SA_ECC6  BI  = M_A_CPU1_SA_CB<6>
  F59  DDR0_SA_ECC3  BI  = M_A_CPU1_SA_CB<3>
  F61  VSS1508  POWER  = GND
  F63  DDR0_SA_DQ30  BI  = M_A_CPU1_SA_DQ<30>
  F65  DDR0_SA_DQ27  BI  = M_A_CPU1_SA_DQ<27>
  F67  VSS1509  POWER  = GND
  F69  DDR0_SA_DQ22  BI  = M_A_CPU1_SA_DQ<22>
  F71  DDR0_SA_DQ19  BI  = M_A_CPU1_SA_DQ<19>
  F73  VSS1510  POWER  = GND
  F75  DDR0_SA_DQ7  BI  = M_A_CPU1_SA_DQ<7>
  F77  DDR0_SA_DQS_DP5  BI  = M_A_CPU1_SA_DQS_DP<5>
  F79  VSS1511  POWER  = GND
  F81  UPI2_RX_DN1  IN  = UPI_CPU0_CPU1_P2P2_DN<1>
  F83  VSS1576  POWER  = GND
  F85  UPI2_TX_DP1  OUT  = UPI_CPU1_CPU0_P2P2_DP<1>
  F87  UPI2_TX_DN3  OUT  = UPI_CPU1_CPU0_P2P2_DN<3>
  F89  VSS1577  POWER  = GND
  G3  VSS1521  POWER  = GND
  G5  RSVD161  BI  = CPU1_RSVD<157>
  G7  VSS1536  POWER  = GND
  G9  DDR0_SB_DQS_DN8  BI  = M_A_CPU1_SB_DQS_DN<8>
  G11  VSS1514  POWER  = GND
  G13  VSS1578  POWER  = GND
  G15  DDR1_SB_DQS_DP8  BI  = M_B_CPU1_SB_DQS_DP<8>
  G17  VSS1516  POWER  = GND
  G19  VSS1579  POWER  = GND
  G21  DDR0_SB_DQS_DN7  BI  = M_A_CPU1_SB_DQS_DN<7>
  G23  VSS1581  POWER  = GND
  G25  VSS1519  POWER  = GND
  G27  DDR0_SB_DQS_DN6  BI  = M_A_CPU1_SB_DQS_DN<6>
  G29  VSS1583  POWER  = GND
  G31  VSS1584  POWER  = GND
  G33  DDR0_SB_DQS_DN4  BI  = M_A_CPU1_SB_DQS_DN<4>
  G35  VSS1523  POWER  = GND
  G37  VSS1585  POWER  = GND
  G39  DDR0_SB_PAR  OUT  = M_A_CPU1_SB_PAR
  G41  VSS1586  POWER  = GND
  G43  VSS1588  POWER  = GND
  G45  DDR0_CLK_DN1  OUT  = M_A_CPU1_CLK_DN<1>
  G48  VSS1527  POWER  = GND
  G50  VSS1590  POWER  = GND
  G52  DDR0_SA_CA1  OUT  = M_A_CPU1_SA_CA<1>
  G54  VSS1591  POWER  = GND
  G56  VSS1592  POWER  = GND
  G58  DDR0_SA_DQS_DN9  BI  = M_A_CPU1_SA_DQS_DN<9>
  G60  VSS1532  POWER  = GND
  G62  VSS1593  POWER  = GND
  G64  DDR0_SA_DQS_DN8  BI  = M_A_CPU1_SA_DQS_DN<8>
  G66  VSS1534  POWER  = GND
  G68  VSS1535  POWER  = GND
  G70  DDR0_SA_DQS_DN7  BI  = M_A_CPU1_SA_DQS_DN<7>
  G72  VSS1594  POWER  = GND
  G74  VSS1538  POWER  = GND
  G76  DDR0_SA_DQ6  BI  = M_A_CPU1_SA_DQ<6>
  G78  DDR0_SA_DQ3  BI  = M_A_CPU1_SA_DQ<3>
  G80  UPI2_RX_DP0  IN  = UPI_CPU0_CPU1_P2P2_DP<0>
  G82  UPI2_RX_DN2  IN  = UPI_CPU0_CPU1_P2P2_DN<2>
  G84  VSS1600  POWER  = GND
  G86  UPI2_TX_DP4  OUT  = UPI_CPU1_CPU0_P2P2_DP<4>
  G88  VSS1601  POWER  = GND
  G90  VSS1604  POWER  = GND
  H2  VSS1546  POWER  = GND
  H4  VSS1615  POWER  = GND
  H6  VSS1621  POWER  = GND
  H8  VSS1626  POWER  = GND
  H10  VSS1605  POWER  = GND
  H12  RSVD162  BI  = TP_CPU1_A0_DEBUG_EN
  H14  VSS1544  POWER  = GND
  H16  VSS1606  POWER  = GND
  H18  DDR1_SB_DQS_DN2  BI  = M_B_CPU1_SB_DQS_DN<2>
  H20  VSS1607  POWER  = GND
  H22  VSS1608  POWER  = GND
  H24  DDR1_SB_DQS_DN1  BI  = M_B_CPU1_SB_DQS_DN<1>
  H26  VSS1609  POWER  = GND
  H28  VSS1610  POWER  = GND
  H30  DDR0_SB_DQS_DN0  BI  = M_A_CPU1_SB_DQS_DN<0>
  H32  VSS1611  POWER  = GND
  H34  VSS1612  POWER  = GND
  H36  DDR1_SB_DQS_DP9  BI  = M_B_CPU1_SB_DQS_DP<9>
  H38  VSS1613  POWER  = GND
  H40  VSS1616  POWER  = GND
  H42  DDR1_SB_CA6  OUT  = M_B_CPU1_SB_CA<6>
  H44  VSS1617  POWER  = GND
  H47  VSS1618  POWER  = GND
  H49  DDR1_SA_CA0  OUT  = M_B_CPU1_SA_CA<0>
  H51  VSS1558  POWER  = GND
  H53  VSS1619  POWER  = GND
  H55  DDR1_SA_DQS_DN4  BI  = M_B_CPU1_SA_DQS_DN<4>
  H57  VSS1560  POWER  = GND
  H59  VSS1620  POWER  = GND
  H61  DDR1_SA_DQS_DN2  BI  = M_B_CPU1_SA_DQS_DN<2>
  H63  VSS1622  POWER  = GND
  H65  VSS1564  POWER  = GND
  H67  DDR0_SA_DQS_DN1  BI  = M_A_CPU1_SA_DQS_DN<1>
  H69  VSS1623  POWER  = GND
  H71  VSS1624  POWER  = GND
  H73  DDR1_SA_DQS_DN0  BI  = M_B_CPU1_SA_DQS_DN<0>
  H75  VSS1567  POWER  = GND
  H77  DDR0_SA_DQS_DN5  BI  = M_A_CPU1_SA_DQS_DN<5>
  H79  VSS1625  POWER  = GND
  H81  VSS1627  POWER  = GND
  H83  UPI2_RX_DP2  IN  = UPI_CPU0_CPU1_P2P2_DP<2>
  H85  UPI2_TX_DN4  OUT  = UPI_CPU1_CPU0_P2P2_DN<4>
  H87  UPI2_TX_DP3  OUT  = UPI_CPU1_CPU0_P2P2_DP<3>
  H89  VCCFA_EHV_FIVRA84  POWER  = PVCCFA_EHV_FIVRA_CPU1
  J3  UPI0_TX_DP0  OUT  = UPI_CPU1_CPU0_P0P1_DP<0>
  J5  VSS1582  POWER  = GND
  J7  VCCFA_EHV_FIVRA86  POWER  = PVCCFA_EHV_FIVRA_CPU1
  J9  VSS1596  POWER  = GND
  J11  VCCFA_EHV_FIVRA85  POWER  = PVCCFA_EHV_FIVRA_CPU1
  J13  RSVD163  BI  = TP_CPU1_PPD
  J15  VSS1628  POWER  = GND
  J17  DDR1_SB_DQ20  BI  = M_B_CPU1_SB_DQ<20>
  J19  DDR1_SB_DQ17  BI  = M_B_CPU1_SB_DQ<17>
  J21  VSS1575  POWER  = GND
  J23  DDR1_SB_DQ12  BI  = M_B_CPU1_SB_DQ<12>
  J25  DDR1_SB_DQ9  BI  = M_B_CPU1_SB_DQ<9>
  J27  VSS1629  POWER  = GND
  J29  DDR0_SB_DQ4  BI  = M_A_CPU1_SB_DQ<4>
  J31  DDR0_SB_DQ1  BI  = M_A_CPU1_SB_DQ<1>
  J33  VSS1630  POWER  = GND
  J35  DDR1_SB_ECC0  BI  = M_B_CPU1_SB_CB<0>
  J37  DDR1_SB_ECC5  BI  = M_B_CPU1_SB_CB<5>
  J39  VSS1580  POWER  = GND
  J41  DDR1_SB_CS_N0  OUT  = M_B_CPU1_SB_CS_N<0>
  J43  DDR1_SB_CA4  OUT  = M_B_CPU1_SB_CA<4>
  J45  VSS1631  POWER  = GND
  J48  DDR1_SA_CA2  OUT  = M_B_CPU1_SA_CA<2>
  J50  DDR1_SA_CS_N1  OUT  = M_B_CPU1_SA_CS_N<1>
  J52  VSS1632  POWER  = GND
  J54  DDR1_SA_ECC4  BI  = M_B_CPU1_SA_CB<4>
  J56  DDR1_SA_ECC1  BI  = M_B_CPU1_SA_CB<1>
  J58  VSS1633  POWER  = GND
  J60  DDR1_SA_DQ20  BI  = M_B_CPU1_SA_DQ<20>
  J62  DDR1_SA_DQ17  BI  = M_B_CPU1_SA_DQ<17>
  J64  VSS1587  POWER  = GND
  J66  DDR0_SA_DQ12  BI  = M_A_CPU1_SA_DQ<12>
  J68  DDR0_SA_DQ9  BI  = M_A_CPU1_SA_DQ<9>
  J70  VSS1589  POWER  = GND
  J72  DDR1_SA_DQ4  BI  = M_B_CPU1_SA_DQ<4>
  J74  DDR1_SA_DQ1  BI  = M_B_CPU1_SA_DQ<1>
  J76  VSS1635  POWER  = GND
  J78  VSS1636  POWER  = GND
  J80  VCCFA_EHV_FIVRA87  POWER  = PVCCFA_EHV_FIVRA_CPU1
  J82  UPI2_RX_DN4  IN  = UPI_CPU0_CPU1_P2P2_DN<4>
  J84  VSS1637  POWER  = GND
  J86  VSS1638  POWER  = GND
  J88  VSS1595  POWER  = GND
  J90  PE4_RX_DN0  IN  = P5E_CPU1_PE4_RX_DN<0>
  K2  VSS1599  POWER  = GND
  K4  UPI0_TX_DN0  OUT  = UPI_CPU1_CPU0_P0P1_DN<0>
  K6  UPI0_RX_DN0  IN  = UPI_CPU0_CPU1_P1P0_DN<0>
  K8  VSS1641  POWER  = GND
  K10  PE0_RX_DN0  IN  = P5E_CPU1_PE0_RX_DN<0>
  K12  VSS1597  POWER  = GND
  K14  VSS1598  POWER  = GND
  K16  DDR1_SB_DQ21  BI  = M_B_CPU1_SB_DQ<21>
  K18  DDR1_SB_DQS_DP2  BI  = M_B_CPU1_SB_DQS_DP<2>
  K20  DDR1_SB_DQ16  BI  = M_B_CPU1_SB_DQ<16>
  K22  DDR1_SB_DQ13  BI  = M_B_CPU1_SB_DQ<13>
  K24  DDR1_SB_DQS_DP1  BI  = M_B_CPU1_SB_DQS_DP<1>
  K26  DDR1_SB_DQ8  BI  = M_B_CPU1_SB_DQ<8>
  K28  DDR0_SB_DQ5  BI  = M_A_CPU1_SB_DQ<5>
  K30  DDR0_SB_DQS_DP0  BI  = M_A_CPU1_SB_DQS_DP<0>
  K32  DDR0_SB_DQ0  BI  = M_A_CPU1_SB_DQ<0>
  K34  DDR1_SB_ECC1  BI  = M_B_CPU1_SB_CB<1>
  K36  DDR1_SB_DQS_DN9  BI  = M_B_CPU1_SB_DQS_DN<9>
  K38  DDR1_SB_ECC4  BI  = M_B_CPU1_SB_CB<4>
  K40  DDR1_SB_CS_N1  OUT  = M_B_CPU1_SB_CS_N<1>
  K42  VSS1602  POWER  = GND
  K44  DDR1_SB_CA2  OUT  = M_B_CPU1_SB_CA<2>
  K47  DDR1_SA_CA4  OUT  = M_B_CPU1_SA_CA<4>
  K49  VSS1603  POWER  = GND
  K51  DDR1_SA_CS_N0  OUT  = M_B_CPU1_SA_CS_N<0>
  K53  DDR1_SA_ECC5  BI  = M_B_CPU1_SA_CB<5>
  K55  DDR1_SA_DQS_DP4  BI  = M_B_CPU1_SA_DQS_DP<4>
  K57  DDR1_SA_ECC0  BI  = M_B_CPU1_SA_CB<0>
  K59  DDR1_SA_DQ21  BI  = M_B_CPU1_SA_DQ<21>
  K61  DDR1_SA_DQS_DP2  BI  = M_B_CPU1_SA_DQS_DP<2>
  K63  DDR1_SA_DQ16  BI  = M_B_CPU1_SA_DQ<16>
  K65  DDR0_SA_DQ13  BI  = M_A_CPU1_SA_DQ<13>
  K67  DDR0_SA_DQS_DP1  BI  = M_A_CPU1_SA_DQS_DP<1>
  K69  DDR0_SA_DQ8  BI  = M_A_CPU1_SA_DQ<8>
  K71  DDR1_SA_DQ5  BI  = M_B_CPU1_SA_DQ<5>
  K73  DDR1_SA_DQS_DP0  BI  = M_B_CPU1_SA_DQS_DP<0>
  K75  DDR1_SA_DQ0  BI  = M_B_CPU1_SA_DQ<0>
  K77  VSS1639  POWER  = GND
  K79  UPI2_RX_DN3  IN  = UPI_CPU0_CPU1_P2P2_DN<3>
  K81  UPI2_RX_DP5  IN  = UPI_CPU0_CPU1_P2P2_DP<5>
  K83  VSS1642  POWER  = GND
  K85  VSS1643  POWER  = GND
  K87  VCCFA_EHV_FIVRA88  POWER  = PVCCFA_EHV_FIVRA_CPU1
  K89  PE4_RX_DP0  IN  = P5E_CPU1_PE4_RX_DP<0>
  L3  UPI0_TX_DP1  OUT  = UPI_CPU1_CPU0_P0P1_DP<1>
  L5  VSS1671  POWER  = GND
  L7  UPI0_RX_DP0  IN  = UPI_CPU0_CPU1_P1P0_DP<0>
  L9  VSS1647  POWER  = GND
  L11  PE0_RX_DP0  IN  = P5E_CPU1_PE0_RX_DP<0>
  L13  VSS1644  POWER  = GND
  L15  VSS1645  POWER  = GND
  L17  VSS1650  POWER  = GND
  L19  VSS1614  POWER  = GND
  L21  VSS1651  POWER  = GND
  L23  VSS1655  POWER  = GND
  L25  VSS1656  POWER  = GND
  L27  VSS1658  POWER  = GND
  L29  VSS1659  POWER  = GND
  L31  VSS1660  POWER  = GND
  L33  VSS1661  POWER  = GND
  L35  VSS1662  POWER  = GND
  L37  VSS1663  POWER  = GND
  L39  VSS1665  POWER  = GND
  L41  VSS1666  POWER  = GND
  L43  VSS1667  POWER  = GND
  L45  VSS1668  POWER  = GND
